# T6G (Grand Teton) — schematic netlist excerpt (pin names and nets, part order shuffled) for the footprints in the layout excerpt that follows; sources: Cadence DE-HDL packaged netlist, KiCad conversion of 04192023_DAF0TMB3IC0_F0TG_MB_C_brd_V02_OCP.brd

R938  Q_RES  4.7K 5% CHIP  pkg 0402LF  page 28 : A = BOOT_RDY_H ; B = PVDD18_S5_P0
PR395  Q_RES  1K 1% CHIP  pkg 0402LF  page 225 : A = PVDD11_S3_P1 ; B = GND

(kicad_pcb
	(version 20260206)
	(generator "pcbnew")
	(generator_version "10.0")
	(general
		(thickness 1.6)
		(legacy_teardrops no)
	)
	(paper "A4")
	(title_block
		(title "04192023_DAF0TMB3IC0_F0TG_MB_C_brd_V02_OCP.brd")
		(comment 1 "Grand Teton / footprints 3170-3171 of 8354")
	)
	(layers
		(0 "F.Cu" signal "TOP")
		(4 "In1.Cu" signal "GND")
		(6 "In2.Cu" signal "IN1")
		(8 "In3.Cu" signal "GND1")
		(10 "In4.Cu" signal "IN2")
		(12 "In5.Cu" signal "GND2")
		(14 "In6.Cu" signal "IN3")
		(16 "In7.Cu" signal "GND3")
		(18 "In8.Cu" signal "VCC")
		(20 "In9.Cu" signal "VCC1")
		(22 "In10.Cu" signal "GND4")
		(24 "In11.Cu" signal "IN4")
		(26 "In12.Cu" signal "GND5")
		(28 "In13.Cu" signal "IN5")
		(30 "In14.Cu" signal "GND6")
		(32 "In15.Cu" signal "IN6")
		(34 "In16.Cu" signal "GND7")
		(2 "B.Cu" signal "BOTTOM")
		(9 "F.Adhes" user "F.Adhesive")
		(11 "B.Adhes" user "B.Adhesive")
		(13 "F.Paste" user "Package Geometry/Pastemask Top")
		(15 "B.Paste" user "Package Geometry/Pastemask Bottom")
		(5 "F.SilkS" user "Ref Des/Silkscreen Top")
		(7 "B.SilkS" user "Ref Des/Silkscreen Bottom")
		(1 "F.Mask" user "Board Geometry/Soldermask Top")
		(3 "B.Mask" user "Board Geometry/Soldermask Bottom")
		(17 "Dwgs.User" user "User.Drawings")
		(19 "Cmts.User" user "User.Comments")
		(21 "Eco1.User" user "User.Eco1")
		(23 "Eco2.User" user "User.Eco2")
		(25 "Edge.Cuts" user "Board Geometry/Outline")
		(27 "Margin" user)
		(31 "F.CrtYd" user "Package Geometry/Place Bound Top")
		(29 "B.CrtYd" user "Package Geometry/Place Bound Bottom")
		(35 "F.Fab" user "Ref Des/Assembly Top")
		(33 "B.Fab" user "Ref Des/Assembly Bottom")
	)
	(footprint ""
		(layer "F.Cu")
		(at 177.469546 -342.23198 90)
		(property "Reference" "PR395"
			(at 0 0 90)
			(layer "F.SilkS")
			(hide yes)
			(effects
				(font
					(size 1.27 1.27)
				)
			)
		)
		(property "Value" ""
			(at 0 0 90)
			(layer "F.Fab")
			(effects
				(font
					(size 1.27 1.27)
				)
			)
		)
		(duplicate_pad_numbers_are_jumpers no)
		(fp_line
			(start 0.7874 -0.4064)
			(end 0.7874 0.4064)
			(stroke
				(width 0.1524)
				(type default)
			)
			(layer "F.SilkS")
		)
		(fp_line
			(start -0.7874 -0.4064)
			(end 0.7874 -0.4064)
			(stroke
				(width 0.1524)
				(type default)
			)
			(layer "F.SilkS")
		)
		(fp_line
			(start 0.7874 0.4064)
			(end -0.7874 0.4064)
			(stroke
				(width 0.1524)
				(type default)
			)
			(layer "F.SilkS")
		)
		(fp_line
			(start -0.7874 0.4064)
			(end -0.7874 -0.4064)
			(stroke
				(width 0.1524)
				(type default)
			)
			(layer "F.SilkS")
		)
		(fp_line
			(start -0.12065 -0.305054)
			(end -0.12065 -0.2794)
			(stroke
				(width 0.1)
				(type default)
			)
			(layer "F.Fab")
		)
		(fp_line
			(start -0.67945 -0.305054)
			(end -0.12065 -0.305054)
			(stroke
				(width 0.1)
				(type default)
			)
			(layer "F.Fab")
		)
		(fp_line
			(start 0.67945 -0.3048)
			(end 0.67945 0.3048)
			(stroke
				(width 0.1)
				(type default)
			)
			(layer "F.Fab")
		)
		(fp_line
			(start 0.12065 -0.3048)
			(end 0.67945 -0.3048)
			(stroke
				(width 0.1)
				(type default)
			)
			(layer "F.Fab")
		)
		(fp_line
			(start 0.12065 -0.2794)
			(end 0.12065 -0.3048)
			(stroke
				(width 0.1)
				(type default)
			)
			(layer "F.Fab")
		)
		(fp_line
			(start -0.12065 -0.2794)
			(end 0.12065 -0.2794)
			(stroke
				(width 0.1)
				(type default)
			)
			(layer "F.Fab")
		)
		(fp_line
			(start 0.120396 0.2794)
			(end -0.12065 0.2794)
			(stroke
				(width 0.1)
				(type default)
			)
			(layer "F.Fab")
		)
		(fp_line
			(start -0.12065 0.2794)
			(end -0.12065 0.3048)
			(stroke
				(width 0.1)
				(type default)
			)
			(layer "F.Fab")
		)
		(fp_line
			(start 0.67945 0.3048)
			(end 0.120396 0.3048)
			(stroke
				(width 0.1)
				(type default)
			)
			(layer "F.Fab")
		)
		(fp_line
			(start 0.120396 0.3048)
			(end 0.120396 0.2794)
			(stroke
				(width 0.1)
				(type default)
			)
			(layer "F.Fab")
		)
		(fp_line
			(start -0.12065 0.3048)
			(end -0.67945 0.3048)
			(stroke
				(width 0.1)
				(type default)
			)
			(layer "F.Fab")
		)
		(fp_line
			(start -0.67945 0.3048)
			(end -0.67945 -0.305054)
			(stroke
				(width 0.1)
				(type default)
			)
			(layer "F.Fab")
		)
		(pad "1" smd circle
			(at -0.40005 0 90)
			(size 0 0)
			(layers "F.Cu" "F.Mask" "F.Paste")
			(net "PVDD11_S3_P1")
		)
		(pad "2" smd circle
			(at 0.40005 0 90)
			(size 0 0)
			(layers "F.Cu" "F.Mask" "F.Paste")
			(net "GND")
		)
	)
	(footprint ""
		(layer "F.Cu")
		(at 402.151088 -329.762612 180)
		(property "Reference" "R938"
			(at 0 0 180)
			(layer "F.SilkS")
			(hide yes)
			(effects
				(font
					(size 1.27 1.27)
				)
			)
		)
		(property "Value" ""
			(at 0 0 180)
			(layer "F.Fab")
			(effects
				(font
					(size 1.27 1.27)
				)
			)
		)
		(duplicate_pad_numbers_are_jumpers no)
		(fp_line
			(start 0.7874 0.4064)
			(end -0.7874 0.4064)
			(stroke
				(width 0.1524)
				(type default)
			)
			(layer "F.SilkS")
		)
		(fp_line
			(start 0.7874 -0.4064)
			(end 0.7874 0.4064)
			(stroke
				(width 0.1524)
				(type default)
			)
			(layer "F.SilkS")
		)
		(fp_line
			(start -0.7874 0.4064)
			(end -0.7874 -0.4064)
			(stroke
				(width 0.1524)
				(type default)
			)
			(layer "F.SilkS")
		)
		(fp_line
			(start -0.7874 -0.4064)
			(end 0.7874 -0.4064)
			(stroke
				(width 0.1524)
				(type default)
			)
			(layer "F.SilkS")
		)
		(fp_line
			(start 0.67945 0.3048)
			(end 0.120396 0.3048)
			(stroke
				(width 0.1)
				(type default)
			)
			(layer "F.Fab")
		)
		(fp_line
			(start 0.67945 -0.3048)
			(end 0.67945 0.3048)
			(stroke
				(width 0.1)
				(type default)
			)
			(layer "F.Fab")
		)
		(fp_line
			(start 0.12065 -0.2794)
			(end 0.12065 -0.3048)
			(stroke
				(width 0.1)
				(type default)
			)
			(layer "F.Fab")
		)
		(fp_line
			(start 0.12065 -0.3048)
			(end 0.67945 -0.3048)
			(stroke
				(width 0.1)
				(type default)
			)
			(layer "F.Fab")
		)
		(fp_line
			(start 0.120396 0.3048)
			(end 0.120396 0.2794)
			(stroke
				(width 0.1)
				(type default)
			)
			(layer "F.Fab")
		)
		(fp_line
			(start 0.120396 0.2794)
			(end -0.12065 0.2794)
			(stroke
				(width 0.1)
				(type default)
			)
			(layer "F.Fab")
		)
		(fp_line
			(start -0.12065 0.3048)
			(end -0.67945 0.3048)
			(stroke
				(width 0.1)
				(type default)
			)
			(layer "F.Fab")
		)
		(fp_line
			(start -0.12065 0.2794)
			(end -0.12065 0.3048)
			(stroke
				(width 0.1)
				(type default)
			)
			(layer "F.Fab")
		)
		(fp_line
			(start -0.12065 -0.2794)
			(end 0.12065 -0.2794)
			(stroke
				(width 0.1)
				(type default)
			)
			(layer "F.Fab")
		)
		(fp_line
			(start -0.12065 -0.305054)
			(end -0.12065 -0.2794)
			(stroke
				(width 0.1)
				(type default)
			)
			(layer "F.Fab")
		)
		(fp_line
			(start -0.67945 0.3048)
			(end -0.67945 -0.305054)
			(stroke
				(width 0.1)
				(type default)
			)
			(layer "F.Fab")
		)
		(fp_line
			(start -0.67945 -0.305054)
			(end -0.12065 -0.305054)
			(stroke
				(width 0.1)
				(type default)
			)
			(layer "F.Fab")
		)
		(pad "1" smd circle
			(at -0.40005 0 180)
			(size 0 0)
			(layers "F.Cu" "F.Mask" "F.Paste")
			(net "BOOT_RDY_H")
		)
		(pad "2" smd circle
			(at 0.40005 0 180)
			(size 0 0)
			(layers "F.Cu" "F.Mask" "F.Paste")
			(net "PVDD18_S5_P0")
		)
	)
)
